# T6G (Grand Teton) — schematic netlist excerpt (pin names and nets, part order shuffled) for the footprints in the layout excerpt that follows; sources: Cadence DE-HDL packaged netlist, KiCad conversion of 04192023_DAF0TMB3IC0_F0TG_MB_C_brd_V02_OCP.brd

R3712  Q_RES  33.2 1% CHIP  pkg 0402LF  page 252 : A = SMB_VR_SENSOR_3V3AUX_SDA ; B = SMB_VR_SENSOR_3V3AUX_SDA_R
R439  Q_RES  0 5% CHIP  pkg 0402LF  page 80 : A = PWRGD_P5V ; B = PWRGD_P5V_R2
H127  HOLE  EMPTY  pkg TH  page 230 : \1\ = NC

(kicad_pcb
	(version 20260206)
	(generator "pcbnew")
	(generator_version "10.0")
	(general
		(thickness 1.6)
		(legacy_teardrops no)
	)
	(paper "A4")
	(title_block
		(title "04192023_DAF0TMB3IC0_F0TG_MB_C_brd_V02_OCP.brd")
		(comment 1 "Grand Teton / footprints 2336-2338 of 8354")
	)
	(layers
		(0 "F.Cu" signal "TOP")
		(4 "In1.Cu" signal "GND")
		(6 "In2.Cu" signal "IN1")
		(8 "In3.Cu" signal "GND1")
		(10 "In4.Cu" signal "IN2")
		(12 "In5.Cu" signal "GND2")
		(14 "In6.Cu" signal "IN3")
		(16 "In7.Cu" signal "GND3")
		(18 "In8.Cu" signal "VCC")
		(20 "In9.Cu" signal "VCC1")
		(22 "In10.Cu" signal "GND4")
		(24 "In11.Cu" signal "IN4")
		(26 "In12.Cu" signal "GND5")
		(28 "In13.Cu" signal "IN5")
		(30 "In14.Cu" signal "GND6")
		(32 "In15.Cu" signal "IN6")
		(34 "In16.Cu" signal "GND7")
		(2 "B.Cu" signal "BOTTOM")
		(9 "F.Adhes" user "F.Adhesive")
		(11 "B.Adhes" user "B.Adhesive")
		(13 "F.Paste" user "Package Geometry/Pastemask Top")
		(15 "B.Paste" user "Package Geometry/Pastemask Bottom")
		(5 "F.SilkS" user "Ref Des/Silkscreen Top")
		(7 "B.SilkS" user "Ref Des/Silkscreen Bottom")
		(1 "F.Mask" user "Board Geometry/Soldermask Top")
		(3 "B.Mask" user "Board Geometry/Soldermask Bottom")
		(17 "Dwgs.User" user "User.Drawings")
		(19 "Cmts.User" user "User.Comments")
		(21 "Eco1.User" user "User.Eco1")
		(23 "Eco2.User" user "User.Eco2")
		(25 "Edge.Cuts" user "Board Geometry/Outline")
		(27 "Margin" user)
		(31 "F.CrtYd" user "Package Geometry/Place Bound Top")
		(29 "B.CrtYd" user "Package Geometry/Place Bound Bottom")
		(35 "F.Fab" user "Ref Des/Assembly Top")
		(33 "B.Fab" user "Ref Des/Assembly Bottom")
	)
	(footprint ""
		(layer "F.Cu")
		(at 163.703 -123.952 180)
		(property "Reference" "R439"
			(at 0 0 180)
			(layer "F.SilkS")
			(hide yes)
			(effects
				(font
					(size 1.27 1.27)
				)
			)
		)
		(property "Value" ""
			(at 0 0 180)
			(layer "F.Fab")
			(effects
				(font
					(size 1.27 1.27)
				)
			)
		)
		(duplicate_pad_numbers_are_jumpers no)
		(fp_line
			(start 0.7874 0.4064)
			(end -0.7874 0.4064)
			(stroke
				(width 0.1524)
				(type default)
			)
			(layer "F.SilkS")
		)
		(fp_line
			(start 0.7874 -0.4064)
			(end 0.7874 0.4064)
			(stroke
				(width 0.1524)
				(type default)
			)
			(layer "F.SilkS")
		)
		(fp_line
			(start -0.7874 0.4064)
			(end -0.7874 -0.4064)
			(stroke
				(width 0.1524)
				(type default)
			)
			(layer "F.SilkS")
		)
		(fp_line
			(start -0.7874 -0.4064)
			(end 0.7874 -0.4064)
			(stroke
				(width 0.1524)
				(type default)
			)
			(layer "F.SilkS")
		)
		(fp_line
			(start 0.67945 0.3048)
			(end 0.120396 0.3048)
			(stroke
				(width 0.1)
				(type default)
			)
			(layer "F.Fab")
		)
		(fp_line
			(start 0.67945 -0.3048)
			(end 0.67945 0.3048)
			(stroke
				(width 0.1)
				(type default)
			)
			(layer "F.Fab")
		)
		(fp_line
			(start 0.12065 -0.2794)
			(end 0.12065 -0.3048)
			(stroke
				(width 0.1)
				(type default)
			)
			(layer "F.Fab")
		)
		(fp_line
			(start 0.12065 -0.3048)
			(end 0.67945 -0.3048)
			(stroke
				(width 0.1)
				(type default)
			)
			(layer "F.Fab")
		)
		(fp_line
			(start 0.120396 0.3048)
			(end 0.120396 0.2794)
			(stroke
				(width 0.1)
				(type default)
			)
			(layer "F.Fab")
		)
		(fp_line
			(start 0.120396 0.2794)
			(end -0.12065 0.2794)
			(stroke
				(width 0.1)
				(type default)
			)
			(layer "F.Fab")
		)
		(fp_line
			(start -0.12065 0.3048)
			(end -0.67945 0.3048)
			(stroke
				(width 0.1)
				(type default)
			)
			(layer "F.Fab")
		)
		(fp_line
			(start -0.12065 0.2794)
			(end -0.12065 0.3048)
			(stroke
				(width 0.1)
				(type default)
			)
			(layer "F.Fab")
		)
		(fp_line
			(start -0.12065 -0.2794)
			(end 0.12065 -0.2794)
			(stroke
				(width 0.1)
				(type default)
			)
			(layer "F.Fab")
		)
		(fp_line
			(start -0.12065 -0.305054)
			(end -0.12065 -0.2794)
			(stroke
				(width 0.1)
				(type default)
			)
			(layer "F.Fab")
		)
		(fp_line
			(start -0.67945 0.3048)
			(end -0.67945 -0.305054)
			(stroke
				(width 0.1)
				(type default)
			)
			(layer "F.Fab")
		)
		(fp_line
			(start -0.67945 -0.305054)
			(end -0.12065 -0.305054)
			(stroke
				(width 0.1)
				(type default)
			)
			(layer "F.Fab")
		)
		(pad "1" smd circle
			(at -0.40005 0 180)
			(size 0 0)
			(layers "F.Cu" "F.Mask" "F.Paste")
			(net "PWRGD_P5V")
		)
		(pad "2" smd circle
			(at 0.40005 0 180)
			(size 0 0)
			(layers "F.Cu" "F.Mask" "F.Paste")
			(net "PWRGD_P5V_R2")
		)
	)
	(footprint ""
		(layer "F.Cu")
		(at 29.954982 -153.765504)
		(property "Reference" "H127"
			(at 5.884164 4.9022 0)
			(unlocked yes)
			(layer "F.SilkS")
			(effects
				(font
					(size 0.7874 0.5842)
					(thickness 0.1524)
				)
				(justify left)
			)
		)
		(property "Value" ""
			(at 0 0 0)
			(layer "F.Fab")
			(effects
				(font
					(size 1.27 1.27)
				)
			)
		)
		(duplicate_pad_numbers_are_jumpers no)
		(fp_circle
			(center 0 0)
			(end 5.8166 0)
			(stroke
				(width 0.1524)
				(type default)
			)
			(fill no)
			(layer "F.SilkS")
		)
		(fp_circle
			(center 0 0)
			(end 5.8166 0)
			(stroke
				(width 0.1524)
				(type default)
			)
			(fill no)
			(layer "B.SilkS")
		)
		(fp_circle
			(center 0 0)
			(end 5.8166 0)
			(stroke
				(width 0.1)
				(type default)
			)
			(fill no)
			(layer "B.Fab")
		)
		(fp_circle
			(center 0 0)
			(end 5.8166 0)
			(stroke
				(width 0.1)
				(type default)
			)
			(fill no)
			(layer "F.Fab")
		)
		(pad "" np_thru_hole circle
			(at 0 0)
			(size 10.0076 10.0076)
			(drill 10.0076)
			(layers "*.Cu" "*.Mask")
			(clearance 0.381)
			(thermal_gap 0.381)
		)
	)
	(footprint ""
		(layer "F.Cu")
		(at 271.085056 -123.86437 180)
		(property "Reference" "R3712"
			(at 0 0 180)
			(layer "F.SilkS")
			(hide yes)
			(effects
				(font
					(size 1.27 1.27)
				)
			)
		)
		(property "Value" ""
			(at 0 0 180)
			(layer "F.Fab")
			(effects
				(font
					(size 1.27 1.27)
				)
			)
		)
		(duplicate_pad_numbers_are_jumpers no)
		(fp_line
			(start 0.7874 0.4064)
			(end -0.7874 0.4064)
			(stroke
				(width 0.1524)
				(type default)
			)
			(layer "F.SilkS")
		)
		(fp_line
			(start 0.7874 -0.4064)
			(end 0.7874 0.4064)
			(stroke
				(width 0.1524)
				(type default)
			)
			(layer "F.SilkS")
		)
		(fp_line
			(start -0.7874 0.4064)
			(end -0.7874 -0.4064)
			(stroke
				(width 0.1524)
				(type default)
			)
			(layer "F.SilkS")
		)
		(fp_line
			(start -0.7874 -0.4064)
			(end 0.7874 -0.4064)
			(stroke
				(width 0.1524)
				(type default)
			)
			(layer "F.SilkS")
		)
		(fp_line
			(start 0.67945 0.3048)
			(end 0.120396 0.3048)
			(stroke
				(width 0.1)
				(type default)
			)
			(layer "F.Fab")
		)
		(fp_line
			(start 0.67945 -0.3048)
			(end 0.67945 0.3048)
			(stroke
				(width 0.1)
				(type default)
			)
			(layer "F.Fab")
		)
		(fp_line
			(start 0.12065 -0.2794)
			(end 0.12065 -0.3048)
			(stroke
				(width 0.1)
				(type default)
			)
			(layer "F.Fab")
		)
		(fp_line
			(start 0.12065 -0.3048)
			(end 0.67945 -0.3048)
			(stroke
				(width 0.1)
				(type default)
			)
			(layer "F.Fab")
		)
		(fp_line
			(start 0.120396 0.3048)
			(end 0.120396 0.2794)
			(stroke
				(width 0.1)
				(type default)
			)
			(layer "F.Fab")
		)
		(fp_line
			(start 0.120396 0.2794)
			(end -0.12065 0.2794)
			(stroke
				(width 0.1)
				(type default)
			)
			(layer "F.Fab")
		)
		(fp_line
			(start -0.12065 0.3048)
			(end -0.67945 0.3048)
			(stroke
				(width 0.1)
				(type default)
			)
			(layer "F.Fab")
		)
		(fp_line
			(start -0.12065 0.2794)
			(end -0.12065 0.3048)
			(stroke
				(width 0.1)
				(type default)
			)
			(layer "F.Fab")
		)
		(fp_line
			(start -0.12065 -0.2794)
			(end 0.12065 -0.2794)
			(stroke
				(width 0.1)
				(type default)
			)
			(layer "F.Fab")
		)
		(fp_line
			(start -0.12065 -0.305054)
			(end -0.12065 -0.2794)
			(stroke
				(width 0.1)
				(type default)
			)
			(layer "F.Fab")
		)
		(fp_line
			(start -0.67945 0.3048)
			(end -0.67945 -0.305054)
			(stroke
				(width 0.1)
				(type default)
			)
			(layer "F.Fab")
		)
		(fp_line
			(start -0.67945 -0.305054)
			(end -0.12065 -0.305054)
			(stroke
				(width 0.1)
				(type default)
			)
			(layer "F.Fab")
		)
		(pad "1" smd circle
			(at -0.40005 0 180)
			(size 0 0)
			(layers "F.Cu" "F.Mask" "F.Paste")
			(net "SMB_VR_SENSOR_3V3AUX_SDA")
		)
		(pad "2" smd circle
			(at 0.40005 0 180)
			(size 0 0)
			(layers "F.Cu" "F.Mask" "F.Paste")
			(net "SMB_VR_SENSOR_3V3AUX_SDA_R")
		)
	)
)
